(kicad_pcb
	(version 20260206)
	(generator "pcbnew")
	(generator_version "10.0")
	(general
		(thickness 1.6)
		(legacy_teardrops no)
	)
	(paper "A4")
	(title_block
		(title "01162023_DA0F0TEBIF0_F0T_Expander_BD_F_brd_V02_OCP.brd")
		(comment 1 "Grand Teton / footprints 8025-8032 of 9728")
	)
	(layers
		(0 "F.Cu" signal "TOP")
		(4 "In1.Cu" signal "GND")
		(6 "In2.Cu" signal "VCC")
		(8 "In3.Cu" signal "VCC1")
		(10 "In4.Cu" signal "GND1")
		(12 "In5.Cu" signal "IN1")
		(14 "In6.Cu" signal "GND2")
		(16 "In7.Cu" signal "IN2")
		(18 "In8.Cu" signal "GND3")
		(20 "In9.Cu" signal "IN3")
		(22 "In10.Cu" signal "GND4")
		(24 "In11.Cu" signal "IN4")
		(26 "In12.Cu" signal "GND5")
		(28 "In13.Cu" signal "IN5")
		(30 "In14.Cu" signal "GND6")
		(32 "In15.Cu" signal "IN6")
		(34 "In16.Cu" signal "GND7")
		(2 "B.Cu" signal "BOTTOM")
		(9 "F.Adhes" user "F.Adhesive")
		(11 "B.Adhes" user "B.Adhesive")
		(13 "F.Paste" user "Package Geometry/Pastemask Top")
		(15 "B.Paste" user "Package Geometry/Pastemask Bottom")
		(5 "F.SilkS" user "Ref Des/Silkscreen Top")
		(7 "B.SilkS" user "Ref Des/Silkscreen Bottom")
		(1 "F.Mask" user "Board Geometry/Soldermask Top")
		(3 "B.Mask" user "Board Geometry/Soldermask Bottom")
		(17 "Dwgs.User" user "User.Drawings")
		(19 "Cmts.User" user "User.Comments")
		(21 "Eco1.User" user "User.Eco1")
		(23 "Eco2.User" user "User.Eco2")
		(25 "Edge.Cuts" user "Board Geometry/Outline")
		(27 "Margin" user)
		(31 "F.CrtYd" user "Package Geometry/Place Bound Top")
		(29 "B.CrtYd" user "Package Geometry/Place Bound Bottom")
		(35 "F.Fab" user "Ref Des/Assembly Top")
		(33 "B.Fab" user "Ref Des/Assembly Bottom")
	)
	(footprint ""
		(layer "B.Cu")
		(at 111.743236 -303.649634 -90)
		(property "Reference" "PR9"
			(at 0 0 90)
			(layer "B.SilkS")
			(hide yes)
			(effects
				(font
					(size 1.27 1.27)
				)
				(justify mirror)
			)
		)
		(property "Value" ""
			(at 0 0 90)
			(layer "B.Fab")
			(effects
				(font
					(size 1.27 1.27)
				)
				(justify mirror)
			)
		)
		(duplicate_pad_numbers_are_jumpers no)
		(fp_line
			(start -1.2954 0.5842)
			(end 1.2954 0.5842)
			(stroke
				(width 0.1524)
				(type default)
			)
			(layer "B.SilkS")
		)
		(fp_line
			(start 1.2954 0.5842)
			(end 1.2954 -0.5842)
			(stroke
				(width 0.1524)
				(type default)
			)
			(layer "B.SilkS")
		)
		(fp_line
			(start -1.2954 -0.5842)
			(end -1.2954 0.5842)
			(stroke
				(width 0.1524)
				(type default)
			)
			(layer "B.SilkS")
		)
		(fp_line
			(start 1.2954 -0.5842)
			(end -1.2954 -0.5842)
			(stroke
				(width 0.1524)
				(type default)
			)
			(layer "B.SilkS")
		)
		(fp_line
			(start -0.8636 0.4572)
			(end 0.8636 0.4572)
			(stroke
				(width 0.1)
				(type default)
			)
			(layer "B.Fab")
		)
		(fp_line
			(start 0.8636 0.4572)
			(end 0.8636 0.4318)
			(stroke
				(width 0.1)
				(type default)
			)
			(layer "B.Fab")
		)
		(fp_line
			(start 0.8636 0.4318)
			(end 0.8636 0.4064)
			(stroke
				(width 0.1)
				(type default)
			)
			(layer "B.Fab")
		)
		(fp_line
			(start -1.1938 0.4064)
			(end -0.8636 0.4064)
			(stroke
				(width 0.1)
				(type default)
			)
			(layer "B.Fab")
		)
		(fp_line
			(start -0.8636 0.4064)
			(end -0.8636 0.4572)
			(stroke
				(width 0.1)
				(type default)
			)
			(layer "B.Fab")
		)
		(fp_line
			(start 0.8636 0.4064)
			(end 1.1938 0.4064)
			(stroke
				(width 0.1)
				(type default)
			)
			(layer "B.Fab")
		)
		(fp_line
			(start 1.1938 0.4064)
			(end 1.1938 -0.406654)
			(stroke
				(width 0.1)
				(type default)
			)
			(layer "B.Fab")
		)
		(fp_line
			(start -1.1938 -0.406654)
			(end -1.1938 0.4064)
			(stroke
				(width 0.1)
				(type default)
			)
			(layer "B.Fab")
		)
		(fp_line
			(start -0.8636 -0.406654)
			(end -1.1938 -0.406654)
			(stroke
				(width 0.1)
				(type default)
			)
			(layer "B.Fab")
		)
		(fp_line
			(start 0.8636 -0.406654)
			(end 0.8636 -0.4572)
			(stroke
				(width 0.1)
				(type default)
			)
			(layer "B.Fab")
		)
		(fp_line
			(start 1.1938 -0.406654)
			(end 0.8636 -0.406654)
			(stroke
				(width 0.1)
				(type default)
			)
			(layer "B.Fab")
		)
		(fp_line
			(start -0.8636 -0.4572)
			(end -0.8636 -0.406654)
			(stroke
				(width 0.1)
				(type default)
			)
			(layer "B.Fab")
		)
		(fp_line
			(start 0.8636 -0.4572)
			(end -0.8636 -0.4572)
			(stroke
				(width 0.1)
				(type default)
			)
			(layer "B.Fab")
		)
		(pad "1" smd rect
			(at 0.7366 0 180)
			(size 0.7112 0.8128)
			(layers "B.Cu" "B.Mask" "B.Paste")
			(net "P0V8_PEX0")
		)
		(pad "2" smd rect
			(at -0.7366 0 180)
			(size 0.7112 0.8128)
			(layers "B.Cu" "B.Mask" "B.Paste")
			(net "GND")
		)
	)
	(footprint ""
		(layer "B.Cu")
		(at 109.63148 -282.060142 90)
		(property "Reference" "PR101"
			(at 0 0 90)
			(layer "B.SilkS")
			(hide yes)
			(effects
				(font
					(size 1.27 1.27)
				)
				(justify mirror)
			)
		)
		(property "Value" ""
			(at 0 0 90)
			(layer "B.Fab")
			(effects
				(font
					(size 1.27 1.27)
				)
				(justify mirror)
			)
		)
		(duplicate_pad_numbers_are_jumpers no)
		(fp_line
			(start 0.7874 -0.4064)
			(end -0.7874 -0.4064)
			(stroke
				(width 0.1524)
				(type default)
			)
			(layer "B.SilkS")
		)
		(fp_line
			(start -0.7874 -0.4064)
			(end -0.7874 0.4064)
			(stroke
				(width 0.1524)
				(type default)
			)
			(layer "B.SilkS")
		)
		(fp_line
			(start 0.7874 0.4064)
			(end 0.7874 -0.4064)
			(stroke
				(width 0.1524)
				(type default)
			)
			(layer "B.SilkS")
		)
		(fp_line
			(start -0.7874 0.4064)
			(end 0.7874 0.4064)
			(stroke
				(width 0.1524)
				(type default)
			)
			(layer "B.SilkS")
		)
		(fp_line
			(start 0.67945 -0.305054)
			(end 0.12065 -0.305054)
			(stroke
				(width 0.1)
				(type default)
			)
			(layer "B.Fab")
		)
		(fp_line
			(start 0.12065 -0.305054)
			(end 0.12065 -0.2794)
			(stroke
				(width 0.1)
				(type default)
			)
			(layer "B.Fab")
		)
		(fp_line
			(start -0.12065 -0.3048)
			(end -0.67945 -0.3048)
			(stroke
				(width 0.1)
				(type default)
			)
			(layer "B.Fab")
		)
		(fp_line
			(start -0.67945 -0.3048)
			(end -0.67945 0.3048)
			(stroke
				(width 0.1)
				(type default)
			)
			(layer "B.Fab")
		)
		(fp_line
			(start 0.12065 -0.2794)
			(end -0.12065 -0.2794)
			(stroke
				(width 0.1)
				(type default)
			)
			(layer "B.Fab")
		)
		(fp_line
			(start -0.12065 -0.2794)
			(end -0.12065 -0.3048)
			(stroke
				(width 0.1)
				(type default)
			)
			(layer "B.Fab")
		)
		(fp_line
			(start 0.12065 0.2794)
			(end 0.12065 0.3048)
			(stroke
				(width 0.1)
				(type default)
			)
			(layer "B.Fab")
		)
		(fp_line
			(start -0.120396 0.2794)
			(end 0.12065 0.2794)
			(stroke
				(width 0.1)
				(type default)
			)
			(layer "B.Fab")
		)
		(fp_line
			(start 0.67945 0.3048)
			(end 0.67945 -0.305054)
			(stroke
				(width 0.1)
				(type default)
			)
			(layer "B.Fab")
		)
		(fp_line
			(start 0.12065 0.3048)
			(end 0.67945 0.3048)
			(stroke
				(width 0.1)
				(type default)
			)
			(layer "B.Fab")
		)
		(fp_line
			(start -0.120396 0.3048)
			(end -0.120396 0.2794)
			(stroke
				(width 0.1)
				(type default)
			)
			(layer "B.Fab")
		)
		(fp_line
			(start -0.67945 0.3048)
			(end -0.120396 0.3048)
			(stroke
				(width 0.1)
				(type default)
			)
			(layer "B.Fab")
		)
		(pad "1" smd circle
			(at 0.40005 0 270)
			(size 0 0)
			(layers "B.Cu" "B.Mask" "B.Paste")
			(net "SW_P0V8_PEX0_VOS1")
		)
		(pad "2" smd circle
			(at -0.40005 0 270)
			(size 0 0)
			(layers "B.Cu" "B.Mask" "B.Paste")
			(net "P0V8_PEX0")
		)
	)
	(footprint ""
		(layer "B.Cu")
		(at 419.141656 -300.174914)
		(property "Reference" "C3511"
			(at 0 0 0)
			(layer "B.SilkS")
			(hide yes)
			(effects
				(font
					(size 1.27 1.27)
				)
				(justify mirror)
			)
		)
		(property "Value" ""
			(at 0 0 0)
			(layer "B.Fab")
			(effects
				(font
					(size 1.27 1.27)
				)
				(justify mirror)
			)
		)
		(duplicate_pad_numbers_are_jumpers no)
		(fp_line
			(start -0.299974 -0.150114)
			(end -0.299974 0.150114)
			(stroke
				(width 0.1)
				(type default)
			)
			(layer "B.Fab")
		)
		(fp_line
			(start -0.299974 0.150114)
			(end 0.299974 0.150114)
			(stroke
				(width 0.1)
				(type default)
			)
			(layer "B.Fab")
		)
		(fp_line
			(start 0.299974 -0.150114)
			(end -0.299974 -0.150114)
			(stroke
				(width 0.1)
				(type default)
			)
			(layer "B.Fab")
		)
		(fp_line
			(start 0.299974 0.150114)
			(end 0.299974 -0.150114)
			(stroke
				(width 0.1)
				(type default)
			)
			(layer "B.Fab")
		)
		(pad "1" smd rect
			(at 0.2667 0 180)
			(size 0.3048 0.381)
			(layers "B.Cu" "B.Mask" "B.Paste")
			(net "P1V8_VDDA_PEX3")
		)
		(pad "2" smd rect
			(at -0.2667 0 180)
			(size 0.3048 0.381)
			(layers "B.Cu" "B.Mask" "B.Paste")
			(net "GND")
		)
	)
	(footprint ""
		(layer "B.Cu")
		(at 303.041558 -300.174914)
		(property "Reference" "C3337"
			(at 0 0 0)
			(layer "B.SilkS")
			(hide yes)
			(effects
				(font
					(size 1.27 1.27)
				)
				(justify mirror)
			)
		)
		(property "Value" ""
			(at 0 0 0)
			(layer "B.Fab")
			(effects
				(font
					(size 1.27 1.27)
				)
				(justify mirror)
			)
		)
		(duplicate_pad_numbers_are_jumpers no)
		(fp_line
			(start -0.299974 -0.150114)
			(end -0.299974 0.150114)
			(stroke
				(width 0.1)
				(type default)
			)
			(layer "B.Fab")
		)
		(fp_line
			(start -0.299974 0.150114)
			(end 0.299974 0.150114)
			(stroke
				(width 0.1)
				(type default)
			)
			(layer "B.Fab")
		)
		(fp_line
			(start 0.299974 -0.150114)
			(end -0.299974 -0.150114)
			(stroke
				(width 0.1)
				(type default)
			)
			(layer "B.Fab")
		)
		(fp_line
			(start 0.299974 0.150114)
			(end 0.299974 -0.150114)
			(stroke
				(width 0.1)
				(type default)
			)
			(layer "B.Fab")
		)
		(pad "1" smd rect
			(at 0.2667 0 180)
			(size 0.3048 0.381)
			(layers "B.Cu" "B.Mask" "B.Paste")
			(net "P1V8_VDDA_PEX2")
		)
		(pad "2" smd rect
			(at -0.2667 0 180)
			(size 0.3048 0.381)
			(layers "B.Cu" "B.Mask" "B.Paste")
			(net "GND")
		)
	)
	(footprint ""
		(layer "B.Cu")
		(at 242.447318 -266.873228 180)
		(property "Reference" "R6135"
			(at 0 0 0)
			(layer "B.SilkS")
			(hide yes)
			(effects
				(font
					(size 1.27 1.27)
				)
				(justify mirror)
			)
		)
		(property "Value" ""
			(at 0 0 0)
			(layer "B.Fab")
			(effects
				(font
					(size 1.27 1.27)
				)
				(justify mirror)
			)
		)
		(duplicate_pad_numbers_are_jumpers no)
		(fp_line
			(start 2.576322 1.1303)
			(end 2.576322 -1.1303)
			(stroke
				(width 0.1524)
				(type default)
			)
			(layer "B.SilkS")
		)
		(fp_line
			(start 2.576322 -1.1303)
			(end -2.576322 -1.1303)
			(stroke
				(width 0.1524)
				(type default)
			)
			(layer "B.SilkS")
		)
		(fp_line
			(start -2.576322 1.1303)
			(end 2.576322 1.1303)
			(stroke
				(width 0.1524)
				(type default)
			)
			(layer "B.SilkS")
		)
		(fp_line
			(start -2.576322 -1.1303)
			(end -2.576322 1.1303)
			(stroke
				(width 0.1524)
				(type default)
			)
			(layer "B.SilkS")
		)
		(fp_line
			(start 1.649984 0.899922)
			(end -1.649984 0.899922)
			(stroke
				(width 0.1)
				(type default)
			)
			(layer "B.Fab")
		)
		(fp_line
			(start 1.649984 -0.899922)
			(end 1.649984 0.899922)
			(stroke
				(width 0.1)
				(type default)
			)
			(layer "B.Fab")
		)
		(fp_line
			(start -1.649984 0.899922)
			(end -1.649984 -0.899922)
			(stroke
				(width 0.1)
				(type default)
			)
			(layer "B.Fab")
		)
		(fp_line
			(start -1.649984 -0.899922)
			(end 1.649984 -0.899922)
			(stroke
				(width 0.1)
				(type default)
			)
			(layer "B.Fab")
		)
		(pad "1A" smd rect
			(at 1.700022 0)
			(size 1.4986 2.0066)
			(layers "B.Cu" "B.Mask" "B.Paste")
			(net "P1V25_PEX2")
		)
		(pad "1B" smd rect
			(at 1.077722 0)
			(size 0.254 0.508)
			(layers "B.Cu" "B.Mask" "B.Paste")
			(net "P1V25_PEX2")
		)
		(pad "2A" smd rect
			(at -1.700022 0)
			(size 1.4986 2.0066)
			(layers "B.Cu" "B.Mask" "B.Paste")
			(net "P1V25_SERDES_VDDPLL_PEX2")
		)
		(pad "2B" smd rect
			(at -1.077722 0)
			(size 0.254 0.508)
			(layers "B.Cu" "B.Mask" "B.Paste")
			(net "P1V25_SERDES_VDDPLL_PEX2")
		)
	)
	(footprint ""
		(layer "B.Cu")
		(at 61.549788 -292.099746 90)
		(property "Reference" "C1207"
			(at 0 0 90)
			(layer "B.SilkS")
			(hide yes)
			(effects
				(font
					(size 1.27 1.27)
				)
				(justify mirror)
			)
		)
		(property "Value" ""
			(at 0 0 90)
			(layer "B.Fab")
			(effects
				(font
					(size 1.27 1.27)
				)
				(justify mirror)
			)
		)
		(duplicate_pad_numbers_are_jumpers no)
		(fp_line
			(start 0.299974 -0.150114)
			(end -0.299974 -0.150114)
			(stroke
				(width 0.1)
				(type default)
			)
			(layer "B.Fab")
		)
		(fp_line
			(start -0.299974 -0.150114)
			(end -0.299974 0.150114)
			(stroke
				(width 0.1)
				(type default)
			)
			(layer "B.Fab")
		)
		(fp_line
			(start 0.299974 0.150114)
			(end 0.299974 -0.150114)
			(stroke
				(width 0.1)
				(type default)
			)
			(layer "B.Fab")
		)
		(fp_line
			(start -0.299974 0.150114)
			(end 0.299974 0.150114)
			(stroke
				(width 0.1)
				(type default)
			)
			(layer "B.Fab")
		)
		(pad "1" smd rect
			(at 0.2667 0 270)
			(size 0.3048 0.381)
			(layers "B.Cu" "B.Mask" "B.Paste")
			(net "P0V8_SERDES_VDDA_PEX0")
		)
		(pad "2" smd rect
			(at -0.2667 0 270)
			(size 0.3048 0.381)
			(layers "B.Cu" "B.Mask" "B.Paste")
			(net "GND")
		)
	)
	(footprint ""
		(layer "B.Cu")
		(at 359.94848 -284.796738 -90)
		(property "Reference" "PC176"
			(at 0 0 90)
			(layer "B.SilkS")
			(hide yes)
			(effects
				(font
					(size 1.27 1.27)
				)
				(justify mirror)
			)
		)
		(property "Value" ""
			(at 0 0 90)
			(layer "B.Fab")
			(effects
				(font
					(size 1.27 1.27)
				)
				(justify mirror)
			)
		)
		(duplicate_pad_numbers_are_jumpers no)
		(fp_line
			(start -1.524 0.762)
			(end 1.524 0.762)
			(stroke
				(width 0.1524)
				(type default)
			)
			(layer "B.SilkS")
		)
		(fp_line
			(start 1.524 0.762)
			(end 1.524 -0.762)
			(stroke
				(width 0.1524)
				(type default)
			)
			(layer "B.SilkS")
		)
		(fp_line
			(start -1.524 -0.762)
			(end -1.524 0.762)
			(stroke
				(width 0.1524)
				(type default)
			)
			(layer "B.SilkS")
		)
		(fp_line
			(start 1.524 -0.762)
			(end -1.524 -0.762)
			(stroke
				(width 0.1524)
				(type default)
			)
			(layer "B.SilkS")
		)
		(fp_line
			(start -1.1049 0.724916)
			(end -1.1049 -0.724916)
			(stroke
				(width 0.1)
				(type default)
			)
			(layer "B.Fab")
		)
		(fp_line
			(start 1.1049 0.724916)
			(end -1.1049 0.724916)
			(stroke
				(width 0.1)
				(type default)
			)
			(layer "B.Fab")
		)
		(fp_line
			(start -1.1049 -0.724916)
			(end 1.1049 -0.724916)
			(stroke
				(width 0.1)
				(type default)
			)
			(layer "B.Fab")
		)
		(fp_line
			(start 1.1049 -0.724916)
			(end 1.1049 0.724916)
			(stroke
				(width 0.1)
				(type default)
			)
			(layer "B.Fab")
		)
		(pad "1" smd rect
			(at 0.889 0 270)
			(size 1.016 1.27)
			(layers "B.Cu" "B.Mask" "B.Paste")
			(net "SW_P12V_P0V8_PEX3_FLT")
		)
		(pad "2" smd rect
			(at -0.889 0 270)
			(size 1.016 1.27)
			(layers "B.Cu" "B.Mask" "B.Paste")
			(net "GND")
		)
	)
	(footprint ""
		(layer "B.Cu")
		(at 329.692 -226.5172 180)
		(property "Reference" "R3107"
			(at 0 0 0)
			(layer "B.SilkS")
			(hide yes)
			(effects
				(font
					(size 1.27 1.27)
				)
				(justify mirror)
			)
		)
		(property "Value" ""
			(at 0 0 0)
			(layer "B.Fab")
			(effects
				(font
					(size 1.27 1.27)
				)
				(justify mirror)
			)
		)
		(duplicate_pad_numbers_are_jumpers no)
		(fp_line
			(start 0.7874 0.4064)
			(end 0.7874 -0.4064)
			(stroke
				(width 0.1524)
				(type default)
			)
			(layer "B.SilkS")
		)
		(fp_line
			(start 0.7874 -0.4064)
			(end -0.7874 -0.4064)
			(stroke
				(width 0.1524)
				(type default)
			)
			(layer "B.SilkS")
		)
		(fp_line
			(start -0.7874 0.4064)
			(end 0.7874 0.4064)
			(stroke
				(width 0.1524)
				(type default)
			)
			(layer "B.SilkS")
		)
		(fp_line
			(start -0.7874 -0.4064)
			(end -0.7874 0.4064)
			(stroke
				(width 0.1524)
				(type default)
			)
			(layer "B.SilkS")
		)
		(fp_line
			(start 0.67945 0.3048)
			(end 0.67945 -0.305054)
			(stroke
				(width 0.1)
				(type default)
			)
			(layer "B.Fab")
		)
		(fp_line
			(start 0.67945 -0.305054)
			(end 0.12065 -0.305054)
			(stroke
				(width 0.1)
				(type default)
			)
			(layer "B.Fab")
		)
		(fp_line
			(start 0.12065 0.3048)
			(end 0.67945 0.3048)
			(stroke
				(width 0.1)
				(type default)
			)
			(layer "B.Fab")
		)
		(fp_line
			(start 0.12065 0.2794)
			(end 0.12065 0.3048)
			(stroke
				(width 0.1)
				(type default)
			)
			(layer "B.Fab")
		)
		(fp_line
			(start 0.12065 -0.2794)
			(end -0.12065 -0.2794)
			(stroke
				(width 0.1)
				(type default)
			)
			(layer "B.Fab")
		)
		(fp_line
			(start 0.12065 -0.305054)
			(end 0.12065 -0.2794)
			(stroke
				(width 0.1)
				(type default)
			)
			(layer "B.Fab")
		)
		(fp_line
			(start -0.120396 0.3048)
			(end -0.120396 0.2794)
			(stroke
				(width 0.1)
				(type default)
			)
			(layer "B.Fab")
		)
		(fp_line
			(start -0.120396 0.2794)
			(end 0.12065 0.2794)
			(stroke
				(width 0.1)
				(type default)
			)
			(layer "B.Fab")
		)
		(fp_line
			(start -0.12065 -0.2794)
			(end -0.12065 -0.3048)
			(stroke
				(width 0.1)
				(type default)
			)
			(layer "B.Fab")
		)
		(fp_line
			(start -0.12065 -0.3048)
			(end -0.67945 -0.3048)
			(stroke
				(width 0.1)
				(type default)
			)
			(layer "B.Fab")
		)
		(fp_line
			(start -0.67945 0.3048)
			(end -0.120396 0.3048)
			(stroke
				(width 0.1)
				(type default)
			)
			(layer "B.Fab")
		)
		(fp_line
			(start -0.67945 -0.3048)
			(end -0.67945 0.3048)
			(stroke
				(width 0.1)
				(type default)
			)
			(layer "B.Fab")
		)
		(pad "1" smd circle
			(at 0.40005 0)
			(size 0 0)
			(layers "B.Cu" "B.Mask" "B.Paste")
			(net "PWRGD_P3V3_AUX_R")
		)
		(pad "2" smd circle
			(at -0.40005 0)
			(size 0 0)
			(layers "B.Cu" "B.Mask" "B.Paste")
			(net "PWR_EN_P1V2_AUX_R")
		)
	)
)
